# T6G (Grand Teton) — schematic netlist excerpt (pin names and nets, part order shuffled) for the footprints in the layout excerpt that follows; sources: Cadence DE-HDL packaged netlist, KiCad conversion of 04192023_DAF0TMB3IC0_F0TG_MB_C_brd_V02_OCP.brd

C1076  Q_CAP  10UF 16V 10% X6S  pkg C0805  page 258 : A = MAX11617_2_VREF ; B = GND
R527  Q_RES  1K 1% CHIP  pkg 0402LF  page 54 : A = PVDD18_S5_P1 ; B = JTAG_CPU1_TMS
PC6817  Q_CAP  22UF 16V 20% X6S  pkg C0805  page 363 : A = SW_P12V_AUX_P0V9_RETIMER_CPU0_FLT ; B = GND
C585  Q_CAP  0.1UF 10V 10% X7S  pkg C0201  page 279 : A = P0V9_CPU0_RT0_2A ; B = GND

(kicad_pcb
	(version 20260206)
	(generator "pcbnew")
	(generator_version "10.0")
	(general
		(thickness 1.6)
		(legacy_teardrops no)
	)
	(paper "A4")
	(title_block
		(title "04192023_DAF0TMB3IC0_F0TG_MB_C_brd_V02_OCP.brd")
		(comment 1 "Grand Teton / footprints 7863-7866 of 8354")
	)
	(layers
		(0 "F.Cu" signal "TOP")
		(4 "In1.Cu" signal "GND")
		(6 "In2.Cu" signal "IN1")
		(8 "In3.Cu" signal "GND1")
		(10 "In4.Cu" signal "IN2")
		(12 "In5.Cu" signal "GND2")
		(14 "In6.Cu" signal "IN3")
		(16 "In7.Cu" signal "GND3")
		(18 "In8.Cu" signal "VCC")
		(20 "In9.Cu" signal "VCC1")
		(22 "In10.Cu" signal "GND4")
		(24 "In11.Cu" signal "IN4")
		(26 "In12.Cu" signal "GND5")
		(28 "In13.Cu" signal "IN5")
		(30 "In14.Cu" signal "GND6")
		(32 "In15.Cu" signal "IN6")
		(34 "In16.Cu" signal "GND7")
		(2 "B.Cu" signal "BOTTOM")
		(9 "F.Adhes" user "F.Adhesive")
		(11 "B.Adhes" user "B.Adhesive")
		(13 "F.Paste" user "Package Geometry/Pastemask Top")
		(15 "B.Paste" user "Package Geometry/Pastemask Bottom")
		(5 "F.SilkS" user "Ref Des/Silkscreen Top")
		(7 "B.SilkS" user "Ref Des/Silkscreen Bottom")
		(1 "F.Mask" user "Board Geometry/Soldermask Top")
		(3 "B.Mask" user "Board Geometry/Soldermask Bottom")
		(17 "Dwgs.User" user "User.Drawings")
		(19 "Cmts.User" user "User.Comments")
		(21 "Eco1.User" user "User.Eco1")
		(23 "Eco2.User" user "User.Eco2")
		(25 "Edge.Cuts" user "Board Geometry/Outline")
		(27 "Margin" user)
		(31 "F.CrtYd" user "Package Geometry/Place Bound Top")
		(29 "B.CrtYd" user "Package Geometry/Place Bound Bottom")
		(35 "F.Fab" user "Ref Des/Assembly Top")
		(33 "B.Fab" user "Ref Des/Assembly Bottom")
	)
	(footprint ""
		(layer "B.Cu")
		(at 458.346302 -405.972264 180)
		(property "Reference" "PC6817"
			(at 0 0 0)
			(layer "B.SilkS")
			(hide yes)
			(effects
				(font
					(size 1.27 1.27)
				)
				(justify mirror)
			)
		)
		(property "Value" ""
			(at 0 0 0)
			(layer "B.Fab")
			(effects
				(font
					(size 1.27 1.27)
				)
				(justify mirror)
			)
		)
		(duplicate_pad_numbers_are_jumpers no)
		(fp_line
			(start 1.524 0.762)
			(end 1.524 -0.762)
			(stroke
				(width 0.1524)
				(type default)
			)
			(layer "B.SilkS")
		)
		(fp_line
			(start 1.524 -0.762)
			(end -1.524 -0.762)
			(stroke
				(width 0.1524)
				(type default)
			)
			(layer "B.SilkS")
		)
		(fp_line
			(start -1.524 0.762)
			(end 1.524 0.762)
			(stroke
				(width 0.1524)
				(type default)
			)
			(layer "B.SilkS")
		)
		(fp_line
			(start -1.524 -0.762)
			(end -1.524 0.762)
			(stroke
				(width 0.1524)
				(type default)
			)
			(layer "B.SilkS")
		)
		(fp_line
			(start 1.1049 0.724916)
			(end -1.1049 0.724916)
			(stroke
				(width 0.1)
				(type default)
			)
			(layer "B.Fab")
		)
		(fp_line
			(start 1.1049 -0.724916)
			(end 1.1049 0.724916)
			(stroke
				(width 0.1)
				(type default)
			)
			(layer "B.Fab")
		)
		(fp_line
			(start -1.1049 0.724916)
			(end -1.1049 -0.724916)
			(stroke
				(width 0.1)
				(type default)
			)
			(layer "B.Fab")
		)
		(fp_line
			(start -1.1049 -0.724916)
			(end 1.1049 -0.724916)
			(stroke
				(width 0.1)
				(type default)
			)
			(layer "B.Fab")
		)
		(pad "1" smd rect
			(at 0.889 0 180)
			(size 1.016 1.27)
			(layers "B.Cu" "B.Mask" "B.Paste")
			(net "SW_P12V_AUX_P0V9_RETIMER_CPU0_FLT")
		)
		(pad "2" smd rect
			(at -0.889 0 180)
			(size 1.016 1.27)
			(layers "B.Cu" "B.Mask" "B.Paste")
			(net "GND")
		)
	)
	(footprint ""
		(layer "B.Cu")
		(at 321.51828 -396.393162 -90)
		(property "Reference" "C585"
			(at 0 0 90)
			(layer "B.SilkS")
			(hide yes)
			(effects
				(font
					(size 1.27 1.27)
				)
				(justify mirror)
			)
		)
		(property "Value" ""
			(at 0 0 90)
			(layer "B.Fab")
			(effects
				(font
					(size 1.27 1.27)
				)
				(justify mirror)
			)
		)
		(duplicate_pad_numbers_are_jumpers no)
		(fp_line
			(start -0.299974 0.150114)
			(end 0.299974 0.150114)
			(stroke
				(width 0.1)
				(type default)
			)
			(layer "B.Fab")
		)
		(fp_line
			(start 0.299974 0.150114)
			(end 0.299974 -0.150114)
			(stroke
				(width 0.1)
				(type default)
			)
			(layer "B.Fab")
		)
		(fp_line
			(start -0.299974 -0.150114)
			(end -0.299974 0.150114)
			(stroke
				(width 0.1)
				(type default)
			)
			(layer "B.Fab")
		)
		(fp_line
			(start 0.299974 -0.150114)
			(end -0.299974 -0.150114)
			(stroke
				(width 0.1)
				(type default)
			)
			(layer "B.Fab")
		)
		(pad "1" smd rect
			(at 0.2667 0 90)
			(size 0.3048 0.381)
			(layers "B.Cu" "B.Mask" "B.Paste")
			(net "P0V9_CPU0_RT0_2A")
		)
		(pad "2" smd rect
			(at -0.2667 0 90)
			(size 0.3048 0.381)
			(layers "B.Cu" "B.Mask" "B.Paste")
			(net "GND")
		)
	)
	(footprint ""
		(layer "B.Cu")
		(at 257.719576 -326.335898 180)
		(property "Reference" "C1076"
			(at 0 0 0)
			(layer "B.SilkS")
			(hide yes)
			(effects
				(font
					(size 1.27 1.27)
				)
				(justify mirror)
			)
		)
		(property "Value" ""
			(at 0 0 0)
			(layer "B.Fab")
			(effects
				(font
					(size 1.27 1.27)
				)
				(justify mirror)
			)
		)
		(duplicate_pad_numbers_are_jumpers no)
		(fp_line
			(start 1.524 0.762)
			(end 1.524 -0.762)
			(stroke
				(width 0.1524)
				(type default)
			)
			(layer "B.SilkS")
		)
		(fp_line
			(start 1.524 -0.762)
			(end -1.524 -0.762)
			(stroke
				(width 0.1524)
				(type default)
			)
			(layer "B.SilkS")
		)
		(fp_line
			(start -1.524 0.762)
			(end 1.524 0.762)
			(stroke
				(width 0.1524)
				(type default)
			)
			(layer "B.SilkS")
		)
		(fp_line
			(start -1.524 -0.762)
			(end -1.524 0.762)
			(stroke
				(width 0.1524)
				(type default)
			)
			(layer "B.SilkS")
		)
		(fp_line
			(start 1.1049 0.724916)
			(end -1.1049 0.724916)
			(stroke
				(width 0.1)
				(type default)
			)
			(layer "B.Fab")
		)
		(fp_line
			(start 1.1049 -0.724916)
			(end 1.1049 0.724916)
			(stroke
				(width 0.1)
				(type default)
			)
			(layer "B.Fab")
		)
		(fp_line
			(start -1.1049 0.724916)
			(end -1.1049 -0.724916)
			(stroke
				(width 0.1)
				(type default)
			)
			(layer "B.Fab")
		)
		(fp_line
			(start -1.1049 -0.724916)
			(end 1.1049 -0.724916)
			(stroke
				(width 0.1)
				(type default)
			)
			(layer "B.Fab")
		)
		(pad "1" smd rect
			(at 0.889 0 180)
			(size 1.016 1.27)
			(layers "B.Cu" "B.Mask" "B.Paste")
			(net "MAX11617_2_VREF")
		)
		(pad "2" smd rect
			(at -0.889 0 180)
			(size 1.016 1.27)
			(layers "B.Cu" "B.Mask" "B.Paste")
			(net "GND")
		)
	)
	(footprint ""
		(layer "B.Cu")
		(at 146.220434 -203.679552 90)
		(property "Reference" "R527"
			(at 0 0 90)
			(layer "B.SilkS")
			(hide yes)
			(effects
				(font
					(size 1.27 1.27)
				)
				(justify mirror)
			)
		)
		(property "Value" ""
			(at 0 0 90)
			(layer "B.Fab")
			(effects
				(font
					(size 1.27 1.27)
				)
				(justify mirror)
			)
		)
		(duplicate_pad_numbers_are_jumpers no)
		(fp_line
			(start 0.7874 -0.4064)
			(end -0.7874 -0.4064)
			(stroke
				(width 0.1524)
				(type default)
			)
			(layer "B.SilkS")
		)
		(fp_line
			(start -0.7874 -0.4064)
			(end -0.7874 0.4064)
			(stroke
				(width 0.1524)
				(type default)
			)
			(layer "B.SilkS")
		)
		(fp_line
			(start 0.7874 0.4064)
			(end 0.7874 -0.4064)
			(stroke
				(width 0.1524)
				(type default)
			)
			(layer "B.SilkS")
		)
		(fp_line
			(start -0.7874 0.4064)
			(end 0.7874 0.4064)
			(stroke
				(width 0.1524)
				(type default)
			)
			(layer "B.SilkS")
		)
		(fp_line
			(start 0.67945 -0.305054)
			(end 0.12065 -0.305054)
			(stroke
				(width 0.1)
				(type default)
			)
			(layer "B.Fab")
		)
		(fp_line
			(start 0.12065 -0.305054)
			(end 0.12065 -0.2794)
			(stroke
				(width 0.1)
				(type default)
			)
			(layer "B.Fab")
		)
		(fp_line
			(start -0.12065 -0.3048)
			(end -0.67945 -0.3048)
			(stroke
				(width 0.1)
				(type default)
			)
			(layer "B.Fab")
		)
		(fp_line
			(start -0.67945 -0.3048)
			(end -0.67945 0.3048)
			(stroke
				(width 0.1)
				(type default)
			)
			(layer "B.Fab")
		)
		(fp_line
			(start 0.12065 -0.2794)
			(end -0.12065 -0.2794)
			(stroke
				(width 0.1)
				(type default)
			)
			(layer "B.Fab")
		)
		(fp_line
			(start -0.12065 -0.2794)
			(end -0.12065 -0.3048)
			(stroke
				(width 0.1)
				(type default)
			)
			(layer "B.Fab")
		)
		(fp_line
			(start 0.12065 0.2794)
			(end 0.12065 0.3048)
			(stroke
				(width 0.1)
				(type default)
			)
			(layer "B.Fab")
		)
		(fp_line
			(start -0.120396 0.2794)
			(end 0.12065 0.2794)
			(stroke
				(width 0.1)
				(type default)
			)
			(layer "B.Fab")
		)
		(fp_line
			(start 0.67945 0.3048)
			(end 0.67945 -0.305054)
			(stroke
				(width 0.1)
				(type default)
			)
			(layer "B.Fab")
		)
		(fp_line
			(start 0.12065 0.3048)
			(end 0.67945 0.3048)
			(stroke
				(width 0.1)
				(type default)
			)
			(layer "B.Fab")
		)
		(fp_line
			(start -0.120396 0.3048)
			(end -0.120396 0.2794)
			(stroke
				(width 0.1)
				(type default)
			)
			(layer "B.Fab")
		)
		(fp_line
			(start -0.67945 0.3048)
			(end -0.120396 0.3048)
			(stroke
				(width 0.1)
				(type default)
			)
			(layer "B.Fab")
		)
		(pad "1" smd circle
			(at 0.40005 0 270)
			(size 0 0)
			(layers "B.Cu" "B.Mask" "B.Paste")
			(net "PVDD18_S5_P1")
		)
		(pad "2" smd circle
			(at -0.40005 0 270)
			(size 0 0)
			(layers "B.Cu" "B.Mask" "B.Paste")
			(net "JTAG_CPU1_TMS")
		)
	)
)
